(kicad_pcb
	(version 20260206)
	(generator "pcbnew")
	(generator_version "10.0")
	(general
		(thickness 1.6)
		(legacy_teardrops no)
	)
	(paper "A4")
	(title_block
		(title "v1-tray-backplane — T6M_tray_BP_c_1023_1120.brd")
		(comment 1 "Open CloudServer (Microsoft) / footprint 92 of 170 (J15), pads 1-20 of 20")
	)
	(layers
		(0 "F.Cu" signal "TOP")
		(4 "In1.Cu" signal "GND")
		(6 "In2.Cu" signal "IN1")
		(8 "In3.Cu" signal "VCC")
		(10 "In4.Cu" signal "VCC1")
		(12 "In5.Cu" signal "IN2")
		(14 "In6.Cu" signal "GND1")
		(2 "B.Cu" signal "BOTTOM")
		(9 "F.Adhes" user "F.Adhesive")
		(11 "B.Adhes" user "B.Adhesive")
		(13 "F.Paste" user "Package Geometry/Pastemask Top")
		(15 "B.Paste" user "Package Geometry/Pastemask Bottom")
		(5 "F.SilkS" user "Ref Des/Silkscreen Top")
		(7 "B.SilkS" user "Ref Des/Silkscreen Bottom")
		(1 "F.Mask" user "Board Geometry/Soldermask Top")
		(3 "B.Mask" user "Board Geometry/Soldermask Bottom")
		(17 "Dwgs.User" user "User.Drawings")
		(19 "Cmts.User" user "User.Comments")
		(21 "Eco1.User" user "User.Eco1")
		(23 "Eco2.User" user "User.Eco2")
		(25 "Edge.Cuts" user "Board Geometry/Outline")
		(27 "Margin" user)
		(31 "F.CrtYd" user "Package Geometry/Place Bound Top")
		(29 "B.CrtYd" user "Package Geometry/Place Bound Bottom")
		(35 "F.Fab" user "Ref Des/Assembly Top")
		(33 "B.Fab" user "Ref Des/Assembly Bottom")
	)
	(footprint ""
		(layer "F.Cu")
		(at 111.694976 -49.795176)
		(property "Reference" "J15"
			(at -19.198082 3.683 90)
			(unlocked yes)
			(layer "F.SilkS")
			(effects
				(font
					(size 0.7874 0.5842)
					(thickness 0.1524)
				)
				(justify left)
			)
		)
		(property "Value" ""
			(at 0 0 0)
			(layer "F.Fab")
			(effects
				(font
					(size 1.27 1.27)
				)
			)
		)
		(duplicate_pad_numbers_are_jumpers no)
		(pad "1" thru_hole circle
			(at 0 4.500118)
			(size 1.5494 1.5494)
			(drill 1.0414)
			(layers "*.Cu" "*.Mask")
			(remove_unused_layers no)
			(net "GND")
			(clearance 0)
		)
		(pad "2" thru_hole circle
			(at -8.58012 4.500118)
			(size 1.5494 1.5494)
			(drill 1.0414)
			(layers "*.Cu" "*.Mask")
			(remove_unused_layers no)
			(net "GND")
			(clearance 0)
		)
		(pad "3" thru_hole circle
			(at 0 14.500098)
			(size 1.5494 1.5494)
			(drill 1.0414)
			(layers "*.Cu" "*.Mask")
			(remove_unused_layers no)
			(net "GND")
			(clearance 0)
		)
		(pad "4" thru_hole circle
			(at -14.249908 9.500108)
			(size 1.5494 1.5494)
			(drill 1.0414)
			(layers "*.Cu" "*.Mask")
			(remove_unused_layers no)
			(net "GND")
			(clearance 0)
		)
		(pad "5" thru_hole circle
			(at -14.249908 19.500088)
			(size 1.5494 1.5494)
			(drill 1.0414)
			(layers "*.Cu" "*.Mask")
			(remove_unused_layers no)
			(net "GND")
			(clearance 0)
		)
		(pad "6" thru_hole circle
			(at 0 24.500078)
			(size 1.5494 1.5494)
			(drill 1.0414)
			(layers "*.Cu" "*.Mask")
			(remove_unused_layers no)
			(net "GND")
			(clearance 0)
		)
		(pad "7" thru_hole circle
			(at -5.679948 24.500078)
			(size 1.5494 1.5494)
			(drill 1.0414)
			(layers "*.Cu" "*.Mask")
			(remove_unused_layers no)
			(net "GND")
			(clearance 0)
		)
		(pad "8" thru_hole circle
			(at -11.079988 24.500078)
			(size 1.5494 1.5494)
			(drill 1.0414)
			(layers "*.Cu" "*.Mask")
			(remove_unused_layers no)
			(net "GND")
			(clearance 0)
		)
		(pad "9" thru_hole circle
			(at -14.249908 29.500068)
			(size 1.5494 1.5494)
			(drill 1.0414)
			(layers "*.Cu" "*.Mask")
			(remove_unused_layers no)
			(net "GND")
			(clearance 0)
		)
		(pad "10" thru_hole circle
			(at -14.249908 39.500048)
			(size 1.5494 1.5494)
			(drill 1.0414)
			(layers "*.Cu" "*.Mask")
			(remove_unused_layers no)
			(net "GND")
			(clearance 0)
		)
		(pad "11" thru_hole circle
			(at 0 27.29992)
			(size 1.3462 1.3462)
			(drill 0.9398)
			(layers "*.Cu" "*.Mask")
			(remove_unused_layers no)
			(net "GND")
			(clearance 0.0508)
			(thermal_gap 0.0508)
		)
		(pad "12" thru_hole circle
			(at 0 31.999936)
			(size 1.3462 1.3462)
			(drill 0.9398)
			(layers "*.Cu" "*.Mask")
			(remove_unused_layers no)
			(net "GND")
			(clearance 0.0508)
			(thermal_gap 0.0508)
		)
		(pad "13" thru_hole circle
			(at 0 36.999926)
			(size 1.3462 1.3462)
			(drill 0.9398)
			(layers "*.Cu" "*.Mask")
			(remove_unused_layers no)
			(net "GND")
			(clearance 0.0508)
			(thermal_gap 0.0508)
		)
		(pad "14" thru_hole circle
			(at -2.329942 41.60012)
			(size 1.3462 1.3462)
			(drill 0.9398)
			(layers "*.Cu" "*.Mask")
			(remove_unused_layers no)
			(net "GND")
			(clearance 0.0508)
			(thermal_gap 0.0508)
		)
		(pad "15" thru_hole circle
			(at -7.130034 41.60012)
			(size 1.3462 1.3462)
			(drill 0.9398)
			(layers "*.Cu" "*.Mask")
			(remove_unused_layers no)
			(net "GND")
			(clearance 0.0508)
			(thermal_gap 0.0508)
		)
		(pad "16" thru_hole circle
			(at -11.929872 41.60012)
			(size 1.3462 1.3462)
			(drill 0.9398)
			(layers "*.Cu" "*.Mask")
			(remove_unused_layers no)
			(net "GND")
			(clearance 0.0508)
			(thermal_gap 0.0508)
		)
		(pad "17" thru_hole circle
			(at -14.249908 27.29992)
			(size 1.3462 1.3462)
			(drill 0.9398)
			(layers "*.Cu" "*.Mask")
			(remove_unused_layers no)
			(net "GND")
			(clearance 0.0508)
			(thermal_gap 0.0508)
		)
		(pad "18" thru_hole circle
			(at -14.249908 31.999936)
			(size 1.3462 1.3462)
			(drill 0.9398)
			(layers "*.Cu" "*.Mask")
			(remove_unused_layers no)
			(net "GND")
			(clearance 0.0508)
			(thermal_gap 0.0508)
		)
		(pad "19" thru_hole circle
			(at -14.249908 36.999926)
			(size 1.3462 1.3462)
			(drill 0.9398)
			(layers "*.Cu" "*.Mask")
			(remove_unused_layers no)
			(net "GND")
			(clearance 0.0508)
			(thermal_gap 0.0508)
		)
		(pad "20" thru_hole circle
			(at 0 34.500058)
			(size 1.2446 1.2446)
			(drill 0.8382)
			(layers "*.Cu" "*.Mask")
			(remove_unused_layers no)
			(net "GND")
			(clearance 0.0508)
			(thermal_gap 0.0508)
		)
	)
)
